# S9S_MB_2U (Grand Teton) — schematic netlist excerpt (pin names and nets, part order shuffled) for the footprints in the layout excerpt that follows; sources: Cadence DE-HDL packaged netlist, KiCad conversion of 03242023_DA0F0TMBIJ0_F0T_Motherboard_J_brd_V01_OCP.brd

C1266  Q_CAP  10UF 6.3V 20% X6S  pkg C0402  page 189 : A = P1V8_PCH_PLL_AUX ; B = GND
R574  Q_RES  4.7K 1% CHIP  pkg 0402LF  page 206 : A = FM_DB2000_VSBEN ; B = GND

(kicad_pcb
	(version 20260206)
	(generator "pcbnew")
	(generator_version "10.0")
	(general
		(thickness 1.6)
		(legacy_teardrops no)
	)
	(paper "A4")
	(title_block
		(title "03242023_DA0F0TMBIJ0_F0T_Motherboard_J_brd_V01_OCP.brd")
		(comment 1 "Grand Teton / footprints 5155-5156 of 6105")
	)
	(layers
		(0 "F.Cu" signal "TOP")
		(4 "In1.Cu" signal "GND")
		(6 "In2.Cu" signal "IN1")
		(8 "In3.Cu" signal "GND1")
		(10 "In4.Cu" signal "IN2")
		(12 "In5.Cu" signal "GND2")
		(14 "In6.Cu" signal "IN3")
		(16 "In7.Cu" signal "GND3")
		(18 "In8.Cu" signal "VCC")
		(20 "In9.Cu" signal "VCC1")
		(22 "In10.Cu" signal "GND4")
		(24 "In11.Cu" signal "IN4")
		(26 "In12.Cu" signal "GND5")
		(28 "In13.Cu" signal "IN5")
		(30 "In14.Cu" signal "GND6")
		(32 "In15.Cu" signal "IN6")
		(34 "In16.Cu" signal "GND7")
		(2 "B.Cu" signal "BOTTOM")
		(9 "F.Adhes" user "F.Adhesive")
		(11 "B.Adhes" user "B.Adhesive")
		(13 "F.Paste" user "Package Geometry/Pastemask Top")
		(15 "B.Paste" user "Package Geometry/Pastemask Bottom")
		(5 "F.SilkS" user "Ref Des/Silkscreen Top")
		(7 "B.SilkS" user "Ref Des/Silkscreen Bottom")
		(1 "F.Mask" user "Board Geometry/Soldermask Top")
		(3 "B.Mask" user "Board Geometry/Soldermask Bottom")
		(17 "Dwgs.User" user "User.Drawings")
		(19 "Cmts.User" user "User.Comments")
		(21 "Eco1.User" user "User.Eco1")
		(23 "Eco2.User" user "User.Eco2")
		(25 "Edge.Cuts" user "Board Geometry/Outline")
		(27 "Margin" user)
		(31 "F.CrtYd" user "Package Geometry/Place Bound Top")
		(29 "B.CrtYd" user "Package Geometry/Place Bound Bottom")
		(35 "F.Fab" user "Ref Des/Assembly Top")
		(33 "B.Fab" user "Ref Des/Assembly Bottom")
	)
	(footprint ""
		(layer "B.Cu")
		(at 237.844076 -126.513082 180)
		(property "Reference" "R574"
			(at 0 0 0)
			(layer "B.SilkS")
			(hide yes)
			(effects
				(font
					(size 1.27 1.27)
				)
				(justify mirror)
			)
		)
		(property "Value" ""
			(at 0 0 0)
			(layer "B.Fab")
			(effects
				(font
					(size 1.27 1.27)
				)
				(justify mirror)
			)
		)
		(duplicate_pad_numbers_are_jumpers no)
		(fp_line
			(start 0.7874 0.4064)
			(end 0.7874 -0.4064)
			(stroke
				(width 0.1524)
				(type default)
			)
			(layer "B.SilkS")
		)
		(fp_line
			(start 0.7874 -0.4064)
			(end -0.7874 -0.4064)
			(stroke
				(width 0.1524)
				(type default)
			)
			(layer "B.SilkS")
		)
		(fp_line
			(start -0.7874 0.4064)
			(end 0.7874 0.4064)
			(stroke
				(width 0.1524)
				(type default)
			)
			(layer "B.SilkS")
		)
		(fp_line
			(start -0.7874 -0.4064)
			(end -0.7874 0.4064)
			(stroke
				(width 0.1524)
				(type default)
			)
			(layer "B.SilkS")
		)
		(fp_line
			(start 0.67945 0.3048)
			(end 0.67945 -0.305054)
			(stroke
				(width 0.1)
				(type default)
			)
			(layer "B.Fab")
		)
		(fp_line
			(start 0.67945 -0.305054)
			(end 0.12065 -0.305054)
			(stroke
				(width 0.1)
				(type default)
			)
			(layer "B.Fab")
		)
		(fp_line
			(start 0.12065 0.3048)
			(end 0.67945 0.3048)
			(stroke
				(width 0.1)
				(type default)
			)
			(layer "B.Fab")
		)
		(fp_line
			(start 0.12065 0.2794)
			(end 0.12065 0.3048)
			(stroke
				(width 0.1)
				(type default)
			)
			(layer "B.Fab")
		)
		(fp_line
			(start 0.12065 -0.2794)
			(end -0.12065 -0.2794)
			(stroke
				(width 0.1)
				(type default)
			)
			(layer "B.Fab")
		)
		(fp_line
			(start 0.12065 -0.305054)
			(end 0.12065 -0.2794)
			(stroke
				(width 0.1)
				(type default)
			)
			(layer "B.Fab")
		)
		(fp_line
			(start -0.120396 0.3048)
			(end -0.120396 0.2794)
			(stroke
				(width 0.1)
				(type default)
			)
			(layer "B.Fab")
		)
		(fp_line
			(start -0.120396 0.2794)
			(end 0.12065 0.2794)
			(stroke
				(width 0.1)
				(type default)
			)
			(layer "B.Fab")
		)
		(fp_line
			(start -0.12065 -0.2794)
			(end -0.12065 -0.3048)
			(stroke
				(width 0.1)
				(type default)
			)
			(layer "B.Fab")
		)
		(fp_line
			(start -0.12065 -0.3048)
			(end -0.67945 -0.3048)
			(stroke
				(width 0.1)
				(type default)
			)
			(layer "B.Fab")
		)
		(fp_line
			(start -0.67945 0.3048)
			(end -0.120396 0.3048)
			(stroke
				(width 0.1)
				(type default)
			)
			(layer "B.Fab")
		)
		(fp_line
			(start -0.67945 -0.3048)
			(end -0.67945 0.3048)
			(stroke
				(width 0.1)
				(type default)
			)
			(layer "B.Fab")
		)
		(pad "1" smd circle
			(at 0.40005 0)
			(size 0 0)
			(layers "B.Cu" "B.Mask" "B.Paste")
			(net "FM_DB2000_VSBEN")
		)
		(pad "2" smd circle
			(at -0.40005 0)
			(size 0 0)
			(layers "B.Cu" "B.Mask" "B.Paste")
			(net "GND")
		)
	)
	(footprint ""
		(layer "B.Cu")
		(at 340.877398 -50.681636 180)
		(property "Reference" "C1266"
			(at 0 0 0)
			(layer "B.SilkS")
			(hide yes)
			(effects
				(font
					(size 1.27 1.27)
				)
				(justify mirror)
			)
		)
		(property "Value" ""
			(at 0 0 0)
			(layer "B.Fab")
			(effects
				(font
					(size 1.27 1.27)
				)
				(justify mirror)
			)
		)
		(duplicate_pad_numbers_are_jumpers no)
		(fp_line
			(start 0.7874 0.4064)
			(end 0.7874 -0.4064)
			(stroke
				(width 0.1524)
				(type default)
			)
			(layer "B.SilkS")
		)
		(fp_line
			(start 0.7874 -0.4064)
			(end -0.7874 -0.4064)
			(stroke
				(width 0.1524)
				(type default)
			)
			(layer "B.SilkS")
		)
		(fp_line
			(start -0.7874 0.4064)
			(end 0.7874 0.4064)
			(stroke
				(width 0.1524)
				(type default)
			)
			(layer "B.SilkS")
		)
		(fp_line
			(start -0.7874 -0.4064)
			(end -0.7874 0.4064)
			(stroke
				(width 0.1524)
				(type default)
			)
			(layer "B.SilkS")
		)
		(fp_line
			(start 0.67945 0.3048)
			(end 0.67945 -0.305054)
			(stroke
				(width 0.1)
				(type default)
			)
			(layer "B.Fab")
		)
		(fp_line
			(start 0.67945 -0.305054)
			(end 0.12065 -0.305054)
			(stroke
				(width 0.1)
				(type default)
			)
			(layer "B.Fab")
		)
		(fp_line
			(start 0.12065 0.3048)
			(end 0.67945 0.3048)
			(stroke
				(width 0.1)
				(type default)
			)
			(layer "B.Fab")
		)
		(fp_line
			(start 0.12065 0.2794)
			(end 0.12065 0.3048)
			(stroke
				(width 0.1)
				(type default)
			)
			(layer "B.Fab")
		)
		(fp_line
			(start 0.12065 -0.2794)
			(end -0.12065 -0.2794)
			(stroke
				(width 0.1)
				(type default)
			)
			(layer "B.Fab")
		)
		(fp_line
			(start 0.12065 -0.305054)
			(end 0.12065 -0.2794)
			(stroke
				(width 0.1)
				(type default)
			)
			(layer "B.Fab")
		)
		(fp_line
			(start -0.120396 0.3048)
			(end -0.120396 0.2794)
			(stroke
				(width 0.1)
				(type default)
			)
			(layer "B.Fab")
		)
		(fp_line
			(start -0.120396 0.2794)
			(end 0.12065 0.2794)
			(stroke
				(width 0.1)
				(type default)
			)
			(layer "B.Fab")
		)
		(fp_line
			(start -0.12065 -0.2794)
			(end -0.12065 -0.3048)
			(stroke
				(width 0.1)
				(type default)
			)
			(layer "B.Fab")
		)
		(fp_line
			(start -0.12065 -0.3048)
			(end -0.67945 -0.3048)
			(stroke
				(width 0.1)
				(type default)
			)
			(layer "B.Fab")
		)
		(fp_line
			(start -0.67945 0.3048)
			(end -0.120396 0.3048)
			(stroke
				(width 0.1)
				(type default)
			)
			(layer "B.Fab")
		)
		(fp_line
			(start -0.67945 -0.3048)
			(end -0.67945 0.3048)
			(stroke
				(width 0.1)
				(type default)
			)
			(layer "B.Fab")
		)
		(pad "1" smd circle
			(at 0.40005 0)
			(size 0 0)
			(layers "B.Cu" "B.Mask" "B.Paste")
			(net "P1V8_PCH_PLL_AUX")
		)
		(pad "2" smd circle
			(at -0.40005 0)
			(size 0 0)
			(layers "B.Cu" "B.Mask" "B.Paste")
			(net "GND")
		)
	)
)
